# S9S_MB_2U (Grand Teton) — schematic netlist excerpt (pin names and nets, part order shuffled) for the footprints in the layout excerpt that follows; sources: Cadence DE-HDL packaged netlist, KiCad conversion of 03242023_DA0F0TMBIJ0_F0T_Motherboard_J_brd_V01_OCP.brd

R27  Q_RES  15.4K 1% CHIP  pkg 0402LF  page 83 : A = PD_CHA_CPU0_DIMM2_SAA ; B = GND
PC496_P1_7  Q_CAP  1UF 16V 10% X6S  pkg C0402  page 288 : A = PVCCIN_CPU1 ; B = GND

(kicad_pcb
	(version 20260206)
	(generator "pcbnew")
	(generator_version "10.0")
	(general
		(thickness 1.6)
		(legacy_teardrops no)
	)
	(paper "A4")
	(title_block
		(title "03242023_DA0F0TMBIJ0_F0T_Motherboard_J_brd_V01_OCP.brd")
		(comment 1 "Grand Teton / footprints 5292-5293 of 6105")
	)
	(layers
		(0 "F.Cu" signal "TOP")
		(4 "In1.Cu" signal "GND")
		(6 "In2.Cu" signal "IN1")
		(8 "In3.Cu" signal "GND1")
		(10 "In4.Cu" signal "IN2")
		(12 "In5.Cu" signal "GND2")
		(14 "In6.Cu" signal "IN3")
		(16 "In7.Cu" signal "GND3")
		(18 "In8.Cu" signal "VCC")
		(20 "In9.Cu" signal "VCC1")
		(22 "In10.Cu" signal "GND4")
		(24 "In11.Cu" signal "IN4")
		(26 "In12.Cu" signal "GND5")
		(28 "In13.Cu" signal "IN5")
		(30 "In14.Cu" signal "GND6")
		(32 "In15.Cu" signal "IN6")
		(34 "In16.Cu" signal "GND7")
		(2 "B.Cu" signal "BOTTOM")
		(9 "F.Adhes" user "F.Adhesive")
		(11 "B.Adhes" user "B.Adhesive")
		(13 "F.Paste" user "Package Geometry/Pastemask Top")
		(15 "B.Paste" user "Package Geometry/Pastemask Bottom")
		(5 "F.SilkS" user "Ref Des/Silkscreen Top")
		(7 "B.SilkS" user "Ref Des/Silkscreen Bottom")
		(1 "F.Mask" user "Board Geometry/Soldermask Top")
		(3 "B.Mask" user "Board Geometry/Soldermask Bottom")
		(17 "Dwgs.User" user "User.Drawings")
		(19 "Cmts.User" user "User.Comments")
		(21 "Eco1.User" user "User.Eco1")
		(23 "Eco2.User" user "User.Eco2")
		(25 "Edge.Cuts" user "Board Geometry/Outline")
		(27 "Margin" user)
		(31 "F.CrtYd" user "Package Geometry/Place Bound Top")
		(29 "B.CrtYd" user "Package Geometry/Place Bound Bottom")
		(35 "F.Fab" user "Ref Des/Assembly Top")
		(33 "B.Fab" user "Ref Des/Assembly Bottom")
	)
	(footprint ""
		(layer "B.Cu")
		(at 83.46948 -331.864208 -90)
		(property "Reference" "PC496_P1_7"
			(at 0 0 90)
			(layer "B.SilkS")
			(hide yes)
			(effects
				(font
					(size 1.27 1.27)
				)
				(justify mirror)
			)
		)
		(property "Value" ""
			(at 0 0 90)
			(layer "B.Fab")
			(effects
				(font
					(size 1.27 1.27)
				)
				(justify mirror)
			)
		)
		(duplicate_pad_numbers_are_jumpers no)
		(fp_line
			(start -0.7874 0.4064)
			(end 0.7874 0.4064)
			(stroke
				(width 0.1524)
				(type default)
			)
			(layer "B.SilkS")
		)
		(fp_line
			(start 0.7874 0.4064)
			(end 0.7874 -0.4064)
			(stroke
				(width 0.1524)
				(type default)
			)
			(layer "B.SilkS")
		)
		(fp_line
			(start -0.7874 -0.4064)
			(end -0.7874 0.4064)
			(stroke
				(width 0.1524)
				(type default)
			)
			(layer "B.SilkS")
		)
		(fp_line
			(start 0.7874 -0.4064)
			(end -0.7874 -0.4064)
			(stroke
				(width 0.1524)
				(type default)
			)
			(layer "B.SilkS")
		)
		(fp_line
			(start -0.67945 0.3048)
			(end -0.120396 0.3048)
			(stroke
				(width 0.1)
				(type default)
			)
			(layer "B.Fab")
		)
		(fp_line
			(start -0.120396 0.3048)
			(end -0.120396 0.2794)
			(stroke
				(width 0.1)
				(type default)
			)
			(layer "B.Fab")
		)
		(fp_line
			(start 0.12065 0.3048)
			(end 0.67945 0.3048)
			(stroke
				(width 0.1)
				(type default)
			)
			(layer "B.Fab")
		)
		(fp_line
			(start 0.67945 0.3048)
			(end 0.67945 -0.305054)
			(stroke
				(width 0.1)
				(type default)
			)
			(layer "B.Fab")
		)
		(fp_line
			(start -0.120396 0.2794)
			(end 0.12065 0.2794)
			(stroke
				(width 0.1)
				(type default)
			)
			(layer "B.Fab")
		)
		(fp_line
			(start 0.12065 0.2794)
			(end 0.12065 0.3048)
			(stroke
				(width 0.1)
				(type default)
			)
			(layer "B.Fab")
		)
		(fp_line
			(start -0.12065 -0.2794)
			(end -0.12065 -0.3048)
			(stroke
				(width 0.1)
				(type default)
			)
			(layer "B.Fab")
		)
		(fp_line
			(start 0.12065 -0.2794)
			(end -0.12065 -0.2794)
			(stroke
				(width 0.1)
				(type default)
			)
			(layer "B.Fab")
		)
		(fp_line
			(start -0.67945 -0.3048)
			(end -0.67945 0.3048)
			(stroke
				(width 0.1)
				(type default)
			)
			(layer "B.Fab")
		)
		(fp_line
			(start -0.12065 -0.3048)
			(end -0.67945 -0.3048)
			(stroke
				(width 0.1)
				(type default)
			)
			(layer "B.Fab")
		)
		(fp_line
			(start 0.12065 -0.305054)
			(end 0.12065 -0.2794)
			(stroke
				(width 0.1)
				(type default)
			)
			(layer "B.Fab")
		)
		(fp_line
			(start 0.67945 -0.305054)
			(end 0.12065 -0.305054)
			(stroke
				(width 0.1)
				(type default)
			)
			(layer "B.Fab")
		)
		(pad "1" smd circle
			(at 0.40005 0 90)
			(size 0 0)
			(layers "B.Cu" "B.Mask" "B.Paste")
			(net "PVCCIN_CPU1")
		)
		(pad "2" smd circle
			(at -0.40005 0 90)
			(size 0 0)
			(layers "B.Cu" "B.Mask" "B.Paste")
			(net "GND")
		)
	)
	(footprint ""
		(layer "B.Cu")
		(at 309.501032 -319.224406)
		(property "Reference" "R27"
			(at 0 0 0)
			(layer "B.SilkS")
			(hide yes)
			(effects
				(font
					(size 1.27 1.27)
				)
				(justify mirror)
			)
		)
		(property "Value" ""
			(at 0 0 0)
			(layer "B.Fab")
			(effects
				(font
					(size 1.27 1.27)
				)
				(justify mirror)
			)
		)
		(duplicate_pad_numbers_are_jumpers no)
		(fp_line
			(start -0.7874 -0.4064)
			(end -0.7874 0.4064)
			(stroke
				(width 0.1524)
				(type default)
			)
			(layer "B.SilkS")
		)
		(fp_line
			(start -0.7874 0.4064)
			(end 0.7874 0.4064)
			(stroke
				(width 0.1524)
				(type default)
			)
			(layer "B.SilkS")
		)
		(fp_line
			(start 0.7874 -0.4064)
			(end -0.7874 -0.4064)
			(stroke
				(width 0.1524)
				(type default)
			)
			(layer "B.SilkS")
		)
		(fp_line
			(start 0.7874 0.4064)
			(end 0.7874 -0.4064)
			(stroke
				(width 0.1524)
				(type default)
			)
			(layer "B.SilkS")
		)
		(fp_line
			(start -0.67945 -0.3048)
			(end -0.67945 0.3048)
			(stroke
				(width 0.1)
				(type default)
			)
			(layer "B.Fab")
		)
		(fp_line
			(start -0.67945 0.3048)
			(end -0.120396 0.3048)
			(stroke
				(width 0.1)
				(type default)
			)
			(layer "B.Fab")
		)
		(fp_line
			(start -0.12065 -0.3048)
			(end -0.67945 -0.3048)
			(stroke
				(width 0.1)
				(type default)
			)
			(layer "B.Fab")
		)
		(fp_line
			(start -0.12065 -0.2794)
			(end -0.12065 -0.3048)
			(stroke
				(width 0.1)
				(type default)
			)
			(layer "B.Fab")
		)
		(fp_line
			(start -0.120396 0.2794)
			(end 0.12065 0.2794)
			(stroke
				(width 0.1)
				(type default)
			)
			(layer "B.Fab")
		)
		(fp_line
			(start -0.120396 0.3048)
			(end -0.120396 0.2794)
			(stroke
				(width 0.1)
				(type default)
			)
			(layer "B.Fab")
		)
		(fp_line
			(start 0.12065 -0.305054)
			(end 0.12065 -0.2794)
			(stroke
				(width 0.1)
				(type default)
			)
			(layer "B.Fab")
		)
		(fp_line
			(start 0.12065 -0.2794)
			(end -0.12065 -0.2794)
			(stroke
				(width 0.1)
				(type default)
			)
			(layer "B.Fab")
		)
		(fp_line
			(start 0.12065 0.2794)
			(end 0.12065 0.3048)
			(stroke
				(width 0.1)
				(type default)
			)
			(layer "B.Fab")
		)
		(fp_line
			(start 0.12065 0.3048)
			(end 0.67945 0.3048)
			(stroke
				(width 0.1)
				(type default)
			)
			(layer "B.Fab")
		)
		(fp_line
			(start 0.67945 -0.305054)
			(end 0.12065 -0.305054)
			(stroke
				(width 0.1)
				(type default)
			)
			(layer "B.Fab")
		)
		(fp_line
			(start 0.67945 0.3048)
			(end 0.67945 -0.305054)
			(stroke
				(width 0.1)
				(type default)
			)
			(layer "B.Fab")
		)
		(pad "1" smd circle
			(at 0.40005 0 180)
			(size 0 0)
			(layers "B.Cu" "B.Mask" "B.Paste")
			(net "PD_CHA_CPU0_DIMM2_SAA")
		)
		(pad "2" smd circle
			(at -0.40005 0 180)
			(size 0 0)
			(layers "B.Cu" "B.Mask" "B.Paste")
			(net "GND")
		)
	)
)
